FILE_TYPE = CONNECTIVITY;
{Allegro Design Entry HDL 17.2-2016 S081 (4005846) 1/11/2022}
"PAGE_NUMBER" = 81;
0"NC";
END.
